(kicad_pcb
	(version 20260206)
	(generator "pcbnew")
	(generator_version "10.0")
	(general
		(thickness 1.6)
		(legacy_teardrops no)
	)
	(paper "A4")
	(title_block
		(title "Bryce Canyon_F.DPB_16315-1-OCP.brd")
		(comment 1 "Bryce Canyon / footprint 407 of 2223 (MONO2), pads 75-147 of 166")
	)
	(layers
		(0 "F.Cu" signal "TOP")
		(4 "In1.Cu" signal "L2GND")
		(6 "In2.Cu" signal "L3")
		(8 "In3.Cu" signal "L4GND")
		(10 "In4.Cu" signal "L5")
		(12 "In5.Cu" signal "L6VCC")
		(14 "In6.Cu" signal "L7VCC")
		(16 "In7.Cu" signal "L8")
		(18 "In8.Cu" signal "L9GND")
		(20 "In9.Cu" signal "L10")
		(22 "In10.Cu" signal "L11GND")
		(2 "B.Cu" signal "BOTTOM")
		(9 "F.Adhes" user "F.Adhesive")
		(11 "B.Adhes" user "B.Adhesive")
		(13 "F.Paste" user "Package Geometry/Pastemask Top")
		(15 "B.Paste" user "Package Geometry/Pastemask Bottom")
		(5 "F.SilkS" user "Ref Des/Silkscreen Top")
		(7 "B.SilkS" user "Ref Des/Silkscreen Bottom")
		(1 "F.Mask" user "Board Geometry/Soldermask Top")
		(3 "B.Mask" user "Board Geometry/Soldermask Bottom")
		(17 "Dwgs.User" user "User.Drawings")
		(19 "Cmts.User" user "User.Comments")
		(21 "Eco1.User" user "User.Eco1")
		(23 "Eco2.User" user "User.Eco2")
		(25 "Edge.Cuts" user "Board Geometry/Outline")
		(27 "Margin" user)
		(31 "F.CrtYd" user "Package Geometry/Place Bound Top")
		(29 "B.CrtYd" user "Package Geometry/Place Bound Bottom")
		(35 "F.Fab" user "Ref Des/Assembly Top")
		(33 "B.Fab" user "Ref Des/Assembly Bottom")
	)
	(footprint ""
		(layer "F.Cu")
		(at 239.300004 -14.85011 90)
		(property "Reference" "MONO2"
			(at 0 0 90)
			(layer "F.SilkS")
			(hide yes)
			(effects
				(font
					(size 1.27 1.27)
				)
			)
		)
		(property "Value" "AMP-CONN164-4R-1-GP"
			(at -25.705054 -1.203706 90)
			(unlocked yes)
			(layer "F.Fab")
			(hide yes)
			(effects
				(font
					(size 1.016 1.016)
					(thickness 0.1524)
				)
			)
		)
		(property "Device Type" "PREFIT-164P-890091-1H441"
			(at -25.705054 -2.727706 90)
			(unlocked yes)
			(layer "F.Fab")
			(hide yes)
			(effects
				(font
					(size 1.016 1.016)
					(thickness 0.1524)
				)
			)
		)
		(duplicate_pad_numbers_are_jumpers no)
		(pad "A73" thru_hole circle
			(at 62.349888 -1.249934 90)
			(size 1.0668 1.0668)
			(drill 0.719836)
			(layers "*.Cu" "*.Mask")
			(remove_unused_layers no)
			(net "PCIE_IOM_A_TO_COMP_A_22_DP")
			(clearance 0.1905)
			(thermal_gap 0.1905)
		)
		(pad "A74" thru_hole circle
			(at 63.349886 -3.24993 90)
			(size 1.0668 1.0668)
			(drill 0.719836)
			(layers "*.Cu" "*.Mask")
			(remove_unused_layers no)
			(net "PCIE_IOM_A_TO_COMP_A_22_DN")
			(clearance 0.1905)
			(thermal_gap 0.1905)
		)
		(pad "A75" thru_hole circle
			(at 64.349884 -1.249934 90)
			(size 1.0668 1.0668)
			(drill 0.719836)
			(layers "*.Cu" "*.Mask")
			(remove_unused_layers no)
			(net "GND")
			(clearance 0.1905)
			(thermal_gap 0.1905)
		)
		(pad "A76" thru_hole circle
			(at 65.349882 -3.24993 90)
			(size 1.0668 1.0668)
			(drill 0.719836)
			(layers "*.Cu" "*.Mask")
			(remove_unused_layers no)
			(net "GND")
			(clearance 0.1905)
			(thermal_gap 0.1905)
		)
		(pad "A77" thru_hole circle
			(at 66.34988 -1.249934 90)
			(size 1.0668 1.0668)
			(drill 0.719836)
			(layers "*.Cu" "*.Mask")
			(remove_unused_layers no)
			(net "PCIE_IOM_A_TO_COMP_A_23_DP")
			(clearance 0.1905)
			(thermal_gap 0.1905)
		)
		(pad "A78" thru_hole circle
			(at 67.349878 -3.24993 90)
			(size 1.0668 1.0668)
			(drill 0.719836)
			(layers "*.Cu" "*.Mask")
			(remove_unused_layers no)
			(net "PCIE_IOM_A_TO_COMP_A_23_DN")
			(clearance 0.1905)
			(thermal_gap 0.1905)
		)
		(pad "A79" thru_hole circle
			(at 68.349876 -1.249934 90)
			(size 1.0668 1.0668)
			(drill 0.719836)
			(layers "*.Cu" "*.Mask")
			(remove_unused_layers no)
			(net "GND")
			(clearance 0.1905)
			(thermal_gap 0.1905)
		)
		(pad "A80" thru_hole circle
			(at 69.349874 -3.24993 90)
			(size 1.0668 1.0668)
			(drill 0.719836)
			(layers "*.Cu" "*.Mask")
			(remove_unused_layers no)
			(net "GND")
			(clearance 0.1905)
			(thermal_gap 0.1905)
		)
		(pad "A81" thru_hole circle
			(at 70.350126 -1.249934 90)
			(size 1.0668 1.0668)
			(drill 0.719836)
			(layers "*.Cu" "*.Mask")
			(remove_unused_layers no)
			(net "P12V_A_COMP")
			(clearance 0.1905)
			(thermal_gap 0.1905)
		)
		(pad "A82" thru_hole circle
			(at 71.350124 -3.24993 90)
			(size 1.0668 1.0668)
			(drill 0.719836)
			(layers "*.Cu" "*.Mask")
			(remove_unused_layers no)
			(net "P12V_A_COMP")
			(clearance 0.1905)
			(thermal_gap 0.1905)
		)
		(pad "B1" thru_hole circle
			(at -11.649964 1.249934 90)
			(size 1.0668 1.0668)
			(drill 0.719836)
			(layers "*.Cu" "*.Mask")
			(remove_unused_layers no)
			(net "P12V_A_COMP")
			(clearance 0.1905)
			(thermal_gap 0.1905)
		)
		(pad "B2" thru_hole circle
			(at -10.649966 3.24993 90)
			(size 1.0668 1.0668)
			(drill 0.719836)
			(layers "*.Cu" "*.Mask")
			(remove_unused_layers no)
			(net "P12V_A_COMP")
			(clearance 0.1905)
			(thermal_gap 0.1905)
		)
		(pad "B3" thru_hole circle
			(at -9.649968 1.249934 90)
			(size 1.0668 1.0668)
			(drill 0.719836)
			(layers "*.Cu" "*.Mask")
			(remove_unused_layers no)
			(net "P12V_A_COMP")
			(clearance 0.1905)
			(thermal_gap 0.1905)
		)
		(pad "B4" thru_hole circle
			(at -8.64997 3.24993 90)
			(size 1.0668 1.0668)
			(drill 0.719836)
			(layers "*.Cu" "*.Mask")
			(remove_unused_layers no)
			(net "GND")
			(clearance 0.1905)
			(thermal_gap 0.1905)
		)
		(pad "B5" thru_hole circle
			(at -7.649972 1.249934 90)
			(size 1.0668 1.0668)
			(drill 0.719836)
			(layers "*.Cu" "*.Mask")
			(remove_unused_layers no)
			(net "TP_COMP_A_NCSI_TXEN")
			(clearance 0.1905)
			(thermal_gap 0.1905)
		)
		(pad "B6" thru_hole circle
			(at -6.649974 3.24993 90)
			(size 1.0668 1.0668)
			(drill 0.719836)
			(layers "*.Cu" "*.Mask")
			(remove_unused_layers no)
			(net "TP_COMP_A_NCSI_TXD0")
			(clearance 0.1905)
			(thermal_gap 0.1905)
		)
		(pad "B7" thru_hole circle
			(at -5.649976 1.249934 90)
			(size 1.0668 1.0668)
			(drill 0.719836)
			(layers "*.Cu" "*.Mask")
			(remove_unused_layers no)
			(net "TP_COMP_A_NCSI_TXD1")
			(clearance 0.1905)
			(thermal_gap 0.1905)
		)
		(pad "B8" thru_hole circle
			(at -4.649978 3.24993 90)
			(size 1.0668 1.0668)
			(drill 0.719836)
			(layers "*.Cu" "*.Mask")
			(remove_unused_layers no)
			(net "TP_COMP_A_NCSI_CRSDV")
			(clearance 0.1905)
			(thermal_gap 0.1905)
		)
		(pad "B9" thru_hole circle
			(at -3.64998 1.249934 90)
			(size 1.0668 1.0668)
			(drill 0.719836)
			(layers "*.Cu" "*.Mask")
			(remove_unused_layers no)
			(net "TP_COMP_A_NCSI_RXER")
			(clearance 0.1905)
			(thermal_gap 0.1905)
		)
		(pad "B10" thru_hole circle
			(at -2.649982 3.24993 90)
			(size 1.0668 1.0668)
			(drill 0.719836)
			(layers "*.Cu" "*.Mask")
			(remove_unused_layers no)
			(net "GND")
			(clearance 0.1905)
			(thermal_gap 0.1905)
		)
		(pad "B11" thru_hole circle
			(at -1.649984 1.249934 90)
			(size 1.0668 1.0668)
			(drill 0.719836)
			(layers "*.Cu" "*.Mask")
			(remove_unused_layers no)
			(net "PCIE_COMP_A_TO_IOM_A_RST_3")
			(clearance 0.1905)
			(thermal_gap 0.1905)
		)
		(pad "B12" thru_hole circle
			(at 1.35001 3.24993 90)
			(size 1.0668 1.0668)
			(drill 0.719836)
			(layers "*.Cu" "*.Mask")
			(remove_unused_layers no)
			(net "PCIE_COMP_A_TO_IOM_A_RST_4")
			(clearance 0.1905)
			(thermal_gap 0.1905)
		)
		(pad "B13" thru_hole circle
			(at 2.350008 1.249934 90)
			(size 1.0668 1.0668)
			(drill 0.719836)
			(layers "*.Cu" "*.Mask")
			(remove_unused_layers no)
			(net "PCIE_COMP_A_RST_5")
			(clearance 0.1905)
			(thermal_gap 0.1905)
		)
		(pad "B14" thru_hole circle
			(at 3.350006 3.24993 90)
			(size 1.0668 1.0668)
			(drill 0.719836)
			(layers "*.Cu" "*.Mask")
			(remove_unused_layers no)
			(net "GND")
			(clearance 0.1905)
			(thermal_gap 0.1905)
		)
		(pad "B15" thru_hole circle
			(at 4.350004 1.249934 90)
			(size 1.0668 1.0668)
			(drill 0.719836)
			(layers "*.Cu" "*.Mask")
			(remove_unused_layers no)
			(net "Net_1402")
			(clearance 0.1905)
			(thermal_gap 0.1905)
		)
		(pad "B16" thru_hole circle
			(at 5.350002 3.24993 90)
			(size 1.0668 1.0668)
			(drill 0.719836)
			(layers "*.Cu" "*.Mask")
			(remove_unused_layers no)
			(net "Net_1401")
			(clearance 0.1905)
			(thermal_gap 0.1905)
		)
		(pad "B17" thru_hole circle
			(at 6.35 1.249934 90)
			(size 1.0668 1.0668)
			(drill 0.719836)
			(layers "*.Cu" "*.Mask")
			(remove_unused_layers no)
			(net "GND")
			(clearance 0.1905)
			(thermal_gap 0.1905)
		)
		(pad "B18" thru_hole circle
			(at 7.349998 3.24993 90)
			(size 1.0668 1.0668)
			(drill 0.719836)
			(layers "*.Cu" "*.Mask")
			(remove_unused_layers no)
			(net "GND")
			(clearance 0.1905)
			(thermal_gap 0.1905)
		)
		(pad "B19" thru_hole circle
			(at 8.349996 1.249934 90)
			(size 1.0668 1.0668)
			(drill 0.719836)
			(layers "*.Cu" "*.Mask")
			(remove_unused_layers no)
			(net "Net_1397")
			(clearance 0.1905)
			(thermal_gap 0.1905)
		)
		(pad "B20" thru_hole circle
			(at 9.349994 3.24993 90)
			(size 1.0668 1.0668)
			(drill 0.719836)
			(layers "*.Cu" "*.Mask")
			(remove_unused_layers no)
			(net "Net_1400")
			(clearance 0.1905)
			(thermal_gap 0.1905)
		)
		(pad "B21" thru_hole circle
			(at 10.349992 1.249934 90)
			(size 1.0668 1.0668)
			(drill 0.719836)
			(layers "*.Cu" "*.Mask")
			(remove_unused_layers no)
			(net "GND")
			(clearance 0.1905)
			(thermal_gap 0.1905)
		)
		(pad "B22" thru_hole circle
			(at 11.34999 3.24993 90)
			(size 1.0668 1.0668)
			(drill 0.719836)
			(layers "*.Cu" "*.Mask")
			(remove_unused_layers no)
			(net "GND")
			(clearance 0.1905)
			(thermal_gap 0.1905)
		)
		(pad "B23" thru_hole circle
			(at 12.349988 1.249934 90)
			(size 1.0668 1.0668)
			(drill 0.719836)
			(layers "*.Cu" "*.Mask")
			(remove_unused_layers no)
			(net "Net_1393")
			(clearance 0.1905)
			(thermal_gap 0.1905)
		)
		(pad "B24" thru_hole circle
			(at 13.349986 3.24993 90)
			(size 1.0668 1.0668)
			(drill 0.719836)
			(layers "*.Cu" "*.Mask")
			(remove_unused_layers no)
			(net "Net_1395")
			(clearance 0.1905)
			(thermal_gap 0.1905)
		)
		(pad "B25" thru_hole circle
			(at 14.349984 1.249934 90)
			(size 1.0668 1.0668)
			(drill 0.719836)
			(layers "*.Cu" "*.Mask")
			(remove_unused_layers no)
			(net "GND")
			(clearance 0.1905)
			(thermal_gap 0.1905)
		)
		(pad "B26" thru_hole circle
			(at 15.349982 3.24993 90)
			(size 1.0668 1.0668)
			(drill 0.719836)
			(layers "*.Cu" "*.Mask")
			(remove_unused_layers no)
			(net "GND")
			(clearance 0.1905)
			(thermal_gap 0.1905)
		)
		(pad "B27" thru_hole circle
			(at 16.34998 1.249934 90)
			(size 1.0668 1.0668)
			(drill 0.719836)
			(layers "*.Cu" "*.Mask")
			(remove_unused_layers no)
			(net "Net_1392")
			(clearance 0.1905)
			(thermal_gap 0.1905)
		)
		(pad "B28" thru_hole circle
			(at 17.349978 3.24993 90)
			(size 1.0668 1.0668)
			(drill 0.719836)
			(layers "*.Cu" "*.Mask")
			(remove_unused_layers no)
			(net "Net_1389")
			(clearance 0.1905)
			(thermal_gap 0.1905)
		)
		(pad "B29" thru_hole circle
			(at 18.349976 1.249934 90)
			(size 1.0668 1.0668)
			(drill 0.719836)
			(layers "*.Cu" "*.Mask")
			(remove_unused_layers no)
			(net "GND")
			(clearance 0.1905)
			(thermal_gap 0.1905)
		)
		(pad "B30" thru_hole circle
			(at 19.349974 3.24993 90)
			(size 1.0668 1.0668)
			(drill 0.719836)
			(layers "*.Cu" "*.Mask")
			(remove_unused_layers no)
			(net "GND")
			(clearance 0.1905)
			(thermal_gap 0.1905)
		)
		(pad "B31" thru_hole circle
			(at 20.349972 1.249934 90)
			(size 1.0668 1.0668)
			(drill 0.719836)
			(layers "*.Cu" "*.Mask")
			(remove_unused_layers no)
			(net "PCIE_COMP_A_TO_IOM_A_CLK_3_DP")
			(clearance 0.1905)
			(thermal_gap 0.1905)
		)
		(pad "B32" thru_hole circle
			(at 21.34997 3.24993 90)
			(size 1.0668 1.0668)
			(drill 0.719836)
			(layers "*.Cu" "*.Mask")
			(remove_unused_layers no)
			(net "PCIE_COMP_A_TO_IOM_A_CLK_3_DN")
			(clearance 0.1905)
			(thermal_gap 0.1905)
		)
		(pad "B33" thru_hole circle
			(at 22.349968 1.249934 90)
			(size 1.0668 1.0668)
			(drill 0.719836)
			(layers "*.Cu" "*.Mask")
			(remove_unused_layers no)
			(net "GND")
			(clearance 0.1905)
			(thermal_gap 0.1905)
		)
		(pad "B34" thru_hole circle
			(at 23.349966 3.24993 90)
			(size 1.0668 1.0668)
			(drill 0.719836)
			(layers "*.Cu" "*.Mask")
			(remove_unused_layers no)
			(net "GND")
			(clearance 0.1905)
			(thermal_gap 0.1905)
		)
		(pad "B35" thru_hole circle
			(at 24.349964 1.249934 90)
			(size 1.0668 1.0668)
			(drill 0.719836)
			(layers "*.Cu" "*.Mask")
			(remove_unused_layers no)
			(net "PCIE_COMP_A_TO_IOM_A_12_DP")
			(clearance 0.1905)
			(thermal_gap 0.1905)
		)
		(pad "B36" thru_hole circle
			(at 25.349962 3.24993 90)
			(size 1.0668 1.0668)
			(drill 0.719836)
			(layers "*.Cu" "*.Mask")
			(remove_unused_layers no)
			(net "PCIE_COMP_A_TO_IOM_A_12_DN")
			(clearance 0.1905)
			(thermal_gap 0.1905)
		)
		(pad "B37" thru_hole circle
			(at 26.34996 1.249934 90)
			(size 1.0668 1.0668)
			(drill 0.719836)
			(layers "*.Cu" "*.Mask")
			(remove_unused_layers no)
			(net "GND")
			(clearance 0.1905)
			(thermal_gap 0.1905)
		)
		(pad "B38" thru_hole circle
			(at 27.349958 3.24993 90)
			(size 1.0668 1.0668)
			(drill 0.719836)
			(layers "*.Cu" "*.Mask")
			(remove_unused_layers no)
			(net "GND")
			(clearance 0.1905)
			(thermal_gap 0.1905)
		)
		(pad "B39" thru_hole circle
			(at 28.349956 1.249934 90)
			(size 1.0668 1.0668)
			(drill 0.719836)
			(layers "*.Cu" "*.Mask")
			(remove_unused_layers no)
			(net "PCIE_COMP_A_TO_IOM_A_13_DP")
			(clearance 0.1905)
			(thermal_gap 0.1905)
		)
		(pad "B40" thru_hole circle
			(at 29.349954 3.24993 90)
			(size 1.0668 1.0668)
			(drill 0.719836)
			(layers "*.Cu" "*.Mask")
			(remove_unused_layers no)
			(net "PCIE_COMP_A_TO_IOM_A_13_DN")
			(clearance 0.1905)
			(thermal_gap 0.1905)
		)
		(pad "B41" thru_hole circle
			(at 30.349952 1.249934 90)
			(size 1.0668 1.0668)
			(drill 0.719836)
			(layers "*.Cu" "*.Mask")
			(remove_unused_layers no)
			(net "GND")
			(clearance 0.1905)
			(thermal_gap 0.1905)
		)
		(pad "B42" thru_hole circle
			(at 31.34995 3.24993 90)
			(size 1.0668 1.0668)
			(drill 0.719836)
			(layers "*.Cu" "*.Mask")
			(remove_unused_layers no)
			(net "GND")
			(clearance 0.1905)
			(thermal_gap 0.1905)
		)
		(pad "B43" thru_hole circle
			(at 32.349948 1.249934 90)
			(size 1.0668 1.0668)
			(drill 0.719836)
			(layers "*.Cu" "*.Mask")
			(remove_unused_layers no)
			(net "PCIE_COMP_A_TO_IOM_A_14_DP")
			(clearance 0.1905)
			(thermal_gap 0.1905)
		)
		(pad "B44" thru_hole circle
			(at 33.349946 3.24993 90)
			(size 1.0668 1.0668)
			(drill 0.719836)
			(layers "*.Cu" "*.Mask")
			(remove_unused_layers no)
			(net "PCIE_COMP_A_TO_IOM_A_14_DN")
			(clearance 0.1905)
			(thermal_gap 0.1905)
		)
		(pad "B45" thru_hole circle
			(at 34.349944 1.249934 90)
			(size 1.0668 1.0668)
			(drill 0.719836)
			(layers "*.Cu" "*.Mask")
			(remove_unused_layers no)
			(net "GND")
			(clearance 0.1905)
			(thermal_gap 0.1905)
		)
		(pad "B46" thru_hole circle
			(at 35.349942 3.24993 90)
			(size 1.0668 1.0668)
			(drill 0.719836)
			(layers "*.Cu" "*.Mask")
			(remove_unused_layers no)
			(net "GND")
			(clearance 0.1905)
			(thermal_gap 0.1905)
		)
		(pad "B47" thru_hole circle
			(at 36.34994 1.249934 90)
			(size 1.0668 1.0668)
			(drill 0.719836)
			(layers "*.Cu" "*.Mask")
			(remove_unused_layers no)
			(net "PCIE_COMP_A_TO_IOM_A_15_DP")
			(clearance 0.1905)
			(thermal_gap 0.1905)
		)
		(pad "B48" thru_hole circle
			(at 37.349938 3.24993 90)
			(size 1.0668 1.0668)
			(drill 0.719836)
			(layers "*.Cu" "*.Mask")
			(remove_unused_layers no)
			(net "PCIE_COMP_A_TO_IOM_A_15_DN")
			(clearance 0.1905)
			(thermal_gap 0.1905)
		)
		(pad "B49" thru_hole circle
			(at 38.349936 1.249934 90)
			(size 1.0668 1.0668)
			(drill 0.719836)
			(layers "*.Cu" "*.Mask")
			(remove_unused_layers no)
			(net "GND")
			(clearance 0.1905)
			(thermal_gap 0.1905)
		)
		(pad "B50" thru_hole circle
			(at 39.349934 3.24993 90)
			(size 1.0668 1.0668)
			(drill 0.719836)
			(layers "*.Cu" "*.Mask")
			(remove_unused_layers no)
			(net "GND")
			(clearance 0.1905)
			(thermal_gap 0.1905)
		)
		(pad "B51" thru_hole circle
			(at 40.349932 1.249934 90)
			(size 1.0668 1.0668)
			(drill 0.719836)
			(layers "*.Cu" "*.Mask")
			(remove_unused_layers no)
			(net "PCIE_COMP_A_TO_IOM_A_16_DP")
			(clearance 0.1905)
			(thermal_gap 0.1905)
		)
		(pad "B52" thru_hole circle
			(at 41.34993 3.24993 90)
			(size 1.0668 1.0668)
			(drill 0.719836)
			(layers "*.Cu" "*.Mask")
			(remove_unused_layers no)
			(net "PCIE_COMP_A_TO_IOM_A_16_DN")
			(clearance 0.1905)
			(thermal_gap 0.1905)
		)
		(pad "B53" thru_hole circle
			(at 42.349928 1.249934 90)
			(size 1.0668 1.0668)
			(drill 0.719836)
			(layers "*.Cu" "*.Mask")
			(remove_unused_layers no)
			(net "GND")
			(clearance 0.1905)
			(thermal_gap 0.1905)
		)
		(pad "B54" thru_hole circle
			(at 43.349926 3.24993 90)
			(size 1.0668 1.0668)
			(drill 0.719836)
			(layers "*.Cu" "*.Mask")
			(remove_unused_layers no)
			(net "GND")
			(clearance 0.1905)
			(thermal_gap 0.1905)
		)
		(pad "B55" thru_hole circle
			(at 44.349924 1.249934 90)
			(size 1.0668 1.0668)
			(drill 0.719836)
			(layers "*.Cu" "*.Mask")
			(remove_unused_layers no)
			(net "PCIE_COMP_A_TO_IOM_A_17_DP")
			(clearance 0.1905)
			(thermal_gap 0.1905)
		)
		(pad "B56" thru_hole circle
			(at 45.349922 3.24993 90)
			(size 1.0668 1.0668)
			(drill 0.719836)
			(layers "*.Cu" "*.Mask")
			(remove_unused_layers no)
			(net "PCIE_COMP_A_TO_IOM_A_17_DN")
			(clearance 0.1905)
			(thermal_gap 0.1905)
		)
		(pad "B57" thru_hole circle
			(at 46.34992 1.249934 90)
			(size 1.0668 1.0668)
			(drill 0.719836)
			(layers "*.Cu" "*.Mask")
			(remove_unused_layers no)
			(net "GND")
			(clearance 0.1905)
			(thermal_gap 0.1905)
		)
		(pad "B58" thru_hole circle
			(at 47.349918 3.24993 90)
			(size 1.0668 1.0668)
			(drill 0.719836)
			(layers "*.Cu" "*.Mask")
			(remove_unused_layers no)
			(net "GND")
			(clearance 0.1905)
			(thermal_gap 0.1905)
		)
		(pad "B59" thru_hole circle
			(at 48.349916 1.249934 90)
			(size 1.0668 1.0668)
			(drill 0.719836)
			(layers "*.Cu" "*.Mask")
			(remove_unused_layers no)
			(net "PCIE_COMP_A_TO_IOM_A_18_DP")
			(clearance 0.1905)
			(thermal_gap 0.1905)
		)
		(pad "B60" thru_hole circle
			(at 49.349914 3.24993 90)
			(size 1.0668 1.0668)
			(drill 0.719836)
			(layers "*.Cu" "*.Mask")
			(remove_unused_layers no)
			(net "PCIE_COMP_A_TO_IOM_A_18_DN")
			(clearance 0.1905)
			(thermal_gap 0.1905)
		)
		(pad "B61" thru_hole circle
			(at 50.349912 1.249934 90)
			(size 1.0668 1.0668)
			(drill 0.719836)
			(layers "*.Cu" "*.Mask")
			(remove_unused_layers no)
			(net "GND")
			(clearance 0.1905)
			(thermal_gap 0.1905)
		)
		(pad "B62" thru_hole circle
			(at 51.34991 3.24993 90)
			(size 1.0668 1.0668)
			(drill 0.719836)
			(layers "*.Cu" "*.Mask")
			(remove_unused_layers no)
			(net "GND")
			(clearance 0.1905)
			(thermal_gap 0.1905)
		)
		(pad "B63" thru_hole circle
			(at 52.349908 1.249934 90)
			(size 1.0668 1.0668)
			(drill 0.719836)
			(layers "*.Cu" "*.Mask")
			(remove_unused_layers no)
			(net "PCIE_COMP_A_TO_IOM_A_19_DP")
			(clearance 0.1905)
			(thermal_gap 0.1905)
		)
	)
)
